# T6G (Grand Teton) — schematic netlist excerpt (pin names and nets, part order shuffled) for the footprints in the layout excerpt that follows; sources: Cadence DE-HDL packaged netlist, KiCad conversion of 04192023_DAF0TMB3IC0_F0TG_MB_C_brd_V02_OCP.brd

R8065  Q_RES  1K 1% CHIP  pkg 0402LF  page 200 : A = P3V3_AUX ; B = PWRGD_PVDDIO_P0_R
C651  Q_CAP  4.7UF 6.3V 20% X6S  pkg 0402  page 290 : A = P0V9_CPU0_RT_2D ; B = GND

(kicad_pcb
	(version 20260206)
	(generator "pcbnew")
	(generator_version "10.0")
	(general
		(thickness 1.6)
		(legacy_teardrops no)
	)
	(paper "A4")
	(title_block
		(title "04192023_DAF0TMB3IC0_F0TG_MB_C_brd_V02_OCP.brd")
		(comment 1 "Grand Teton / footprints 8091-8092 of 8354")
	)
	(layers
		(0 "F.Cu" signal "TOP")
		(4 "In1.Cu" signal "GND")
		(6 "In2.Cu" signal "IN1")
		(8 "In3.Cu" signal "GND1")
		(10 "In4.Cu" signal "IN2")
		(12 "In5.Cu" signal "GND2")
		(14 "In6.Cu" signal "IN3")
		(16 "In7.Cu" signal "GND3")
		(18 "In8.Cu" signal "VCC")
		(20 "In9.Cu" signal "VCC1")
		(22 "In10.Cu" signal "GND4")
		(24 "In11.Cu" signal "IN4")
		(26 "In12.Cu" signal "GND5")
		(28 "In13.Cu" signal "IN5")
		(30 "In14.Cu" signal "GND6")
		(32 "In15.Cu" signal "IN6")
		(34 "In16.Cu" signal "GND7")
		(2 "B.Cu" signal "BOTTOM")
		(9 "F.Adhes" user "F.Adhesive")
		(11 "B.Adhes" user "B.Adhesive")
		(13 "F.Paste" user "Package Geometry/Pastemask Top")
		(15 "B.Paste" user "Package Geometry/Pastemask Bottom")
		(5 "F.SilkS" user "Ref Des/Silkscreen Top")
		(7 "B.SilkS" user "Ref Des/Silkscreen Bottom")
		(1 "F.Mask" user "Board Geometry/Soldermask Top")
		(3 "B.Mask" user "Board Geometry/Soldermask Bottom")
		(17 "Dwgs.User" user "User.Drawings")
		(19 "Cmts.User" user "User.Comments")
		(21 "Eco1.User" user "User.Eco1")
		(23 "Eco2.User" user "User.Eco2")
		(25 "Edge.Cuts" user "Board Geometry/Outline")
		(27 "Margin" user)
		(31 "F.CrtYd" user "Package Geometry/Place Bound Top")
		(29 "B.CrtYd" user "Package Geometry/Place Bound Bottom")
		(35 "F.Fab" user "Ref Des/Assembly Top")
		(33 "B.Fab" user "Ref Des/Assembly Bottom")
	)
	(footprint ""
		(layer "B.Cu")
		(at 341.918798 -398.942052 90)
		(property "Reference" "C651"
			(at 0 0 90)
			(layer "B.SilkS")
			(hide yes)
			(effects
				(font
					(size 1.27 1.27)
				)
				(justify mirror)
			)
		)
		(property "Value" ""
			(at 0 0 90)
			(layer "B.Fab")
			(effects
				(font
					(size 1.27 1.27)
				)
				(justify mirror)
			)
		)
		(duplicate_pad_numbers_are_jumpers no)
		(fp_line
			(start 0.7874 -0.4064)
			(end -0.7874 -0.4064)
			(stroke
				(width 0.1524)
				(type default)
			)
			(layer "B.SilkS")
		)
		(fp_line
			(start -0.7874 -0.4064)
			(end -0.7874 0.4064)
			(stroke
				(width 0.1524)
				(type default)
			)
			(layer "B.SilkS")
		)
		(fp_line
			(start 0.7874 0.4064)
			(end 0.7874 -0.4064)
			(stroke
				(width 0.1524)
				(type default)
			)
			(layer "B.SilkS")
		)
		(fp_line
			(start -0.7874 0.4064)
			(end 0.7874 0.4064)
			(stroke
				(width 0.1524)
				(type default)
			)
			(layer "B.SilkS")
		)
		(fp_line
			(start 0.67945 -0.305054)
			(end 0.12065 -0.305054)
			(stroke
				(width 0.1)
				(type default)
			)
			(layer "B.Fab")
		)
		(fp_line
			(start 0.12065 -0.305054)
			(end 0.12065 -0.2794)
			(stroke
				(width 0.1)
				(type default)
			)
			(layer "B.Fab")
		)
		(fp_line
			(start -0.12065 -0.3048)
			(end -0.67945 -0.3048)
			(stroke
				(width 0.1)
				(type default)
			)
			(layer "B.Fab")
		)
		(fp_line
			(start -0.67945 -0.3048)
			(end -0.67945 0.3048)
			(stroke
				(width 0.1)
				(type default)
			)
			(layer "B.Fab")
		)
		(fp_line
			(start 0.12065 -0.2794)
			(end -0.12065 -0.2794)
			(stroke
				(width 0.1)
				(type default)
			)
			(layer "B.Fab")
		)
		(fp_line
			(start -0.12065 -0.2794)
			(end -0.12065 -0.3048)
			(stroke
				(width 0.1)
				(type default)
			)
			(layer "B.Fab")
		)
		(fp_line
			(start 0.12065 0.2794)
			(end 0.12065 0.3048)
			(stroke
				(width 0.1)
				(type default)
			)
			(layer "B.Fab")
		)
		(fp_line
			(start -0.120396 0.2794)
			(end 0.12065 0.2794)
			(stroke
				(width 0.1)
				(type default)
			)
			(layer "B.Fab")
		)
		(fp_line
			(start 0.67945 0.3048)
			(end 0.67945 -0.305054)
			(stroke
				(width 0.1)
				(type default)
			)
			(layer "B.Fab")
		)
		(fp_line
			(start 0.12065 0.3048)
			(end 0.67945 0.3048)
			(stroke
				(width 0.1)
				(type default)
			)
			(layer "B.Fab")
		)
		(fp_line
			(start -0.120396 0.3048)
			(end -0.120396 0.2794)
			(stroke
				(width 0.1)
				(type default)
			)
			(layer "B.Fab")
		)
		(fp_line
			(start -0.67945 0.3048)
			(end -0.120396 0.3048)
			(stroke
				(width 0.1)
				(type default)
			)
			(layer "B.Fab")
		)
		(pad "1" smd circle
			(at 0.40005 0 270)
			(size 0 0)
			(layers "B.Cu" "B.Mask" "B.Paste")
			(net "P0V9_CPU0_RT_2D")
		)
		(pad "2" smd circle
			(at -0.40005 0 270)
			(size 0 0)
			(layers "B.Cu" "B.Mask" "B.Paste")
			(net "GND")
		)
	)
	(footprint ""
		(layer "B.Cu")
		(at 304.419 -359.283 180)
		(property "Reference" "R8065"
			(at 0 0 0)
			(layer "B.SilkS")
			(hide yes)
			(effects
				(font
					(size 1.27 1.27)
				)
				(justify mirror)
			)
		)
		(property "Value" ""
			(at 0 0 0)
			(layer "B.Fab")
			(effects
				(font
					(size 1.27 1.27)
				)
				(justify mirror)
			)
		)
		(duplicate_pad_numbers_are_jumpers no)
		(fp_line
			(start 0.7874 0.4064)
			(end 0.7874 -0.4064)
			(stroke
				(width 0.1524)
				(type default)
			)
			(layer "B.SilkS")
		)
		(fp_line
			(start 0.7874 -0.4064)
			(end -0.7874 -0.4064)
			(stroke
				(width 0.1524)
				(type default)
			)
			(layer "B.SilkS")
		)
		(fp_line
			(start -0.7874 0.4064)
			(end 0.7874 0.4064)
			(stroke
				(width 0.1524)
				(type default)
			)
			(layer "B.SilkS")
		)
		(fp_line
			(start -0.7874 -0.4064)
			(end -0.7874 0.4064)
			(stroke
				(width 0.1524)
				(type default)
			)
			(layer "B.SilkS")
		)
		(fp_line
			(start 0.67945 0.3048)
			(end 0.67945 -0.305054)
			(stroke
				(width 0.1)
				(type default)
			)
			(layer "B.Fab")
		)
		(fp_line
			(start 0.67945 -0.305054)
			(end 0.12065 -0.305054)
			(stroke
				(width 0.1)
				(type default)
			)
			(layer "B.Fab")
		)
		(fp_line
			(start 0.12065 0.3048)
			(end 0.67945 0.3048)
			(stroke
				(width 0.1)
				(type default)
			)
			(layer "B.Fab")
		)
		(fp_line
			(start 0.12065 0.2794)
			(end 0.12065 0.3048)
			(stroke
				(width 0.1)
				(type default)
			)
			(layer "B.Fab")
		)
		(fp_line
			(start 0.12065 -0.2794)
			(end -0.12065 -0.2794)
			(stroke
				(width 0.1)
				(type default)
			)
			(layer "B.Fab")
		)
		(fp_line
			(start 0.12065 -0.305054)
			(end 0.12065 -0.2794)
			(stroke
				(width 0.1)
				(type default)
			)
			(layer "B.Fab")
		)
		(fp_line
			(start -0.120396 0.3048)
			(end -0.120396 0.2794)
			(stroke
				(width 0.1)
				(type default)
			)
			(layer "B.Fab")
		)
		(fp_line
			(start -0.120396 0.2794)
			(end 0.12065 0.2794)
			(stroke
				(width 0.1)
				(type default)
			)
			(layer "B.Fab")
		)
		(fp_line
			(start -0.12065 -0.2794)
			(end -0.12065 -0.3048)
			(stroke
				(width 0.1)
				(type default)
			)
			(layer "B.Fab")
		)
		(fp_line
			(start -0.12065 -0.3048)
			(end -0.67945 -0.3048)
			(stroke
				(width 0.1)
				(type default)
			)
			(layer "B.Fab")
		)
		(fp_line
			(start -0.67945 0.3048)
			(end -0.120396 0.3048)
			(stroke
				(width 0.1)
				(type default)
			)
			(layer "B.Fab")
		)
		(fp_line
			(start -0.67945 -0.3048)
			(end -0.67945 0.3048)
			(stroke
				(width 0.1)
				(type default)
			)
			(layer "B.Fab")
		)
		(pad "1" smd circle
			(at 0.40005 0)
			(size 0 0)
			(layers "B.Cu" "B.Mask" "B.Paste")
			(net "P3V3_AUX")
		)
		(pad "2" smd circle
			(at -0.40005 0)
			(size 0 0)
			(layers "B.Cu" "B.Mask" "B.Paste")
			(net "PWRGD_PVDDIO_P0_R")
		)
	)
)
